(kicad_pcb
	(version 20260206)
	(generator "pcbnew")
	(generator_version "10.0")
	(general
		(thickness 1.6)
		(legacy_teardrops no)
	)
	(paper "A4")
	(title_block
		(title "Bryce Canyon_IOM_M2_16342-2_OCP.brd")
		(comment 1 "Bryce Canyon / footprints 859-864 of 1146")
	)
	(layers
		(0 "F.Cu" signal "TOP")
		(4 "In1.Cu" signal "L2GND")
		(6 "In2.Cu" signal "L3")
		(8 "In3.Cu" signal "L4VCC")
		(10 "In4.Cu" signal "L5VCC")
		(12 "In5.Cu" signal "L6")
		(14 "In6.Cu" signal "L7GND")
		(2 "B.Cu" signal "BOTTOM")
		(9 "F.Adhes" user "F.Adhesive")
		(11 "B.Adhes" user "B.Adhesive")
		(13 "F.Paste" user "Package Geometry/Pastemask Top")
		(15 "B.Paste" user "Package Geometry/Pastemask Bottom")
		(5 "F.SilkS" user "Ref Des/Silkscreen Top")
		(7 "B.SilkS" user "Ref Des/Silkscreen Bottom")
		(1 "F.Mask" user "Board Geometry/Soldermask Top")
		(3 "B.Mask" user "Board Geometry/Soldermask Bottom")
		(17 "Dwgs.User" user "User.Drawings")
		(19 "Cmts.User" user "User.Comments")
		(21 "Eco1.User" user "User.Eco1")
		(23 "Eco2.User" user "User.Eco2")
		(25 "Edge.Cuts" user "Board Geometry/Outline")
		(27 "Margin" user)
		(31 "F.CrtYd" user "Package Geometry/Place Bound Top")
		(29 "B.CrtYd" user "Package Geometry/Place Bound Bottom")
		(35 "F.Fab" user "Ref Des/Assembly Top")
		(33 "B.Fab" user "Ref Des/Assembly Bottom")
	)
	(footprint ""
		(layer "B.Cu")
		(at 50.938684 -127.383286 -90)
		(property "Reference" "R294"
			(at 0 0 90)
			(layer "B.SilkS")
			(hide yes)
			(effects
				(font
					(size 1.27 1.27)
				)
				(justify mirror)
			)
		)
		(property "Value" "0R2J-2-GP"
			(at -0.064008 -3.993896 270)
			(unlocked yes)
			(layer "B.Fab")
			(hide yes)
			(effects
				(font
					(size 1.016 1.016)
					(thickness 0.1524)
				)
				(justify mirror)
			)
		)
		(property "Device Type" "R402H16"
			(at -0.064008 -5.517896 270)
			(unlocked yes)
			(layer "B.Fab")
			(hide yes)
			(effects
				(font
					(size 1.016 1.016)
					(thickness 0.1524)
				)
				(justify mirror)
			)
		)
		(duplicate_pad_numbers_are_jumpers no)
		(fp_line
			(start -0.508 -0.9398)
			(end 0.508 -0.9398)
			(stroke
				(width 0.1524)
				(type default)
			)
			(layer "B.SilkS")
		)
		(fp_line
			(start 0.508 -0.9398)
			(end 0.508 0.9398)
			(stroke
				(width 0.1524)
				(type default)
			)
			(layer "B.SilkS")
		)
		(fp_rect
			(start 0.508 0.9398)
			(end -0.508 -0.9398)
			(stroke
				(width 0)
				(type default)
			)
			(fill no)
			(layer "B.CrtYd")
		)
		(fp_rect
			(start 0.508 0.9398)
			(end -0.508 -0.9398)
			(stroke
				(width 0)
				(type default)
			)
			(fill no)
			(layer "B.Fab")
		)
		(pad "1" smd custom
			(at 0 -0.4445 90)
			(size 0.1397 0.1397)
			(layers "B.Cu" "B.Mask" "B.Paste")
			(net "P12V_A_PGOOD")
			(options
				(clearance outline)
				(anchor circle)
			)
			(primitives
				(gr_poly
					(pts
						(arc
							(start -0.1778 0.2794)
							(mid -0.249642 0.249642)
							(end -0.2794 0.1778)
						)
						(arc
							(start -0.2794 -0.1778)
							(mid -0.249642 -0.249642)
							(end -0.1778 -0.2794)
						)
						(arc
							(start 0.1778 -0.2794)
							(mid 0.249642 -0.249642)
							(end 0.2794 -0.1778)
						)
						(arc
							(start 0.2794 0.1778)
							(mid 0.249642 0.249642)
							(end 0.1778 0.2794)
						)
					)
					(width 0)
					(fill yes)
				)
			)
		)
		(pad "2" smd custom
			(at 0 0.4445 90)
			(size 0.1397 0.1397)
			(layers "B.Cu" "B.Mask" "B.Paste")
			(net "P12V_A_PGOOD_R")
			(options
				(clearance outline)
				(anchor circle)
			)
			(primitives
				(gr_poly
					(pts
						(arc
							(start -0.1778 0.2794)
							(mid -0.249642 0.249642)
							(end -0.2794 0.1778)
						)
						(arc
							(start -0.2794 -0.1778)
							(mid -0.249642 -0.249642)
							(end -0.1778 -0.2794)
						)
						(arc
							(start 0.1778 -0.2794)
							(mid 0.249642 -0.249642)
							(end 0.2794 -0.1778)
						)
						(arc
							(start 0.2794 0.1778)
							(mid 0.249642 0.249642)
							(end 0.1778 0.2794)
						)
					)
					(width 0)
					(fill yes)
				)
			)
		)
	)
	(footprint ""
		(layer "B.Cu")
		(at 17.723612 -131.007358 180)
		(property "Reference" "R241"
			(at 0 0 0)
			(layer "B.SilkS")
			(hide yes)
			(effects
				(font
					(size 1.27 1.27)
				)
				(justify mirror)
			)
		)
		(property "Value" "120R2F-GP"
			(at -0.064008 -3.993896 180)
			(unlocked yes)
			(layer "B.Fab")
			(hide yes)
			(effects
				(font
					(size 1.016 1.016)
					(thickness 0.1524)
				)
				(justify mirror)
			)
		)
		(property "Device Type" "R402H16"
			(at -0.064008 -5.517896 180)
			(unlocked yes)
			(layer "B.Fab")
			(hide yes)
			(effects
				(font
					(size 1.016 1.016)
					(thickness 0.1524)
				)
				(justify mirror)
			)
		)
		(duplicate_pad_numbers_are_jumpers no)
		(fp_line
			(start 0.508 -0.9398)
			(end 0.508 0.9398)
			(stroke
				(width 0.1524)
				(type default)
			)
			(layer "B.SilkS")
		)
		(fp_line
			(start -0.508 -0.9398)
			(end 0.508 -0.9398)
			(stroke
				(width 0.1524)
				(type default)
			)
			(layer "B.SilkS")
		)
		(fp_rect
			(start 0.508 0.9398)
			(end -0.508 -0.9398)
			(stroke
				(width 0)
				(type default)
			)
			(fill no)
			(layer "B.CrtYd")
		)
		(fp_rect
			(start 0.508 0.9398)
			(end -0.508 -0.9398)
			(stroke
				(width 0)
				(type default)
			)
			(fill no)
			(layer "B.Fab")
		)
		(pad "1" smd custom
			(at 0 -0.4445)
			(size 0.1397 0.1397)
			(layers "B.Cu" "B.Mask" "B.Paste")
			(net "MEMA_3")
			(options
				(clearance outline)
				(anchor circle)
			)
			(primitives
				(gr_poly
					(pts
						(arc
							(start -0.1778 0.2794)
							(mid -0.249642 0.249642)
							(end -0.2794 0.1778)
						)
						(arc
							(start -0.2794 -0.1778)
							(mid -0.249642 -0.249642)
							(end -0.1778 -0.2794)
						)
						(arc
							(start 0.1778 -0.2794)
							(mid 0.249642 -0.249642)
							(end 0.2794 -0.1778)
						)
						(arc
							(start 0.2794 0.1778)
							(mid 0.249642 0.249642)
							(end 0.1778 0.2794)
						)
					)
					(width 0)
					(fill yes)
				)
			)
		)
		(pad "2" smd custom
			(at 0 0.4445)
			(size 0.1397 0.1397)
			(layers "B.Cu" "B.Mask" "B.Paste")
			(net "P1V2_STBY")
			(options
				(clearance outline)
				(anchor circle)
			)
			(primitives
				(gr_poly
					(pts
						(arc
							(start -0.1778 0.2794)
							(mid -0.249642 0.249642)
							(end -0.2794 0.1778)
						)
						(arc
							(start -0.2794 -0.1778)
							(mid -0.249642 -0.249642)
							(end -0.1778 -0.2794)
						)
						(arc
							(start 0.1778 -0.2794)
							(mid 0.249642 -0.249642)
							(end 0.2794 -0.1778)
						)
						(arc
							(start 0.2794 0.1778)
							(mid 0.249642 0.249642)
							(end 0.1778 0.2794)
						)
					)
					(width 0)
					(fill yes)
				)
			)
		)
	)
	(footprint ""
		(layer "B.Cu")
		(at 63.6778 -138.0744 90)
		(property "Reference" "R186"
			(at 0 0 90)
			(layer "B.SilkS")
			(hide yes)
			(effects
				(font
					(size 1.27 1.27)
				)
				(justify mirror)
			)
		)
		(property "Value" "2K2R2F-GP"
			(at -0.064008 -3.993896 90)
			(unlocked yes)
			(layer "B.Fab")
			(hide yes)
			(effects
				(font
					(size 1.016 1.016)
					(thickness 0.1524)
				)
				(justify mirror)
			)
		)
		(property "Device Type" "R402H16"
			(at -0.064008 -5.517896 90)
			(unlocked yes)
			(layer "B.Fab")
			(hide yes)
			(effects
				(font
					(size 1.016 1.016)
					(thickness 0.1524)
				)
				(justify mirror)
			)
		)
		(duplicate_pad_numbers_are_jumpers no)
		(fp_line
			(start 0.508 -0.9398)
			(end 0.508 0.9398)
			(stroke
				(width 0.1524)
				(type default)
			)
			(layer "B.SilkS")
		)
		(fp_line
			(start -0.508 -0.9398)
			(end 0.508 -0.9398)
			(stroke
				(width 0.1524)
				(type default)
			)
			(layer "B.SilkS")
		)
		(fp_rect
			(start 0.508 0.9398)
			(end -0.508 -0.9398)
			(stroke
				(width 0)
				(type default)
			)
			(fill no)
			(layer "B.CrtYd")
		)
		(fp_rect
			(start 0.508 0.9398)
			(end -0.508 -0.9398)
			(stroke
				(width 0)
				(type default)
			)
			(fill no)
			(layer "B.Fab")
		)
		(pad "1" smd custom
			(at 0 -0.4445 270)
			(size 0.1397 0.1397)
			(layers "B.Cu" "B.Mask" "B.Paste")
			(net "I2C_M2_2_SDA")
			(options
				(clearance outline)
				(anchor circle)
			)
			(primitives
				(gr_poly
					(pts
						(arc
							(start -0.1778 0.2794)
							(mid -0.249642 0.249642)
							(end -0.2794 0.1778)
						)
						(arc
							(start -0.2794 -0.1778)
							(mid -0.249642 -0.249642)
							(end -0.1778 -0.2794)
						)
						(arc
							(start 0.1778 -0.2794)
							(mid 0.249642 -0.249642)
							(end 0.2794 -0.1778)
						)
						(arc
							(start 0.2794 0.1778)
							(mid 0.249642 0.249642)
							(end 0.1778 0.2794)
						)
					)
					(width 0)
					(fill yes)
				)
			)
		)
		(pad "2" smd custom
			(at 0 0.4445 270)
			(size 0.1397 0.1397)
			(layers "B.Cu" "B.Mask" "B.Paste")
			(net "P3V3_STBY")
			(options
				(clearance outline)
				(anchor circle)
			)
			(primitives
				(gr_poly
					(pts
						(arc
							(start -0.1778 0.2794)
							(mid -0.249642 0.249642)
							(end -0.2794 0.1778)
						)
						(arc
							(start -0.2794 -0.1778)
							(mid -0.249642 -0.249642)
							(end -0.1778 -0.2794)
						)
						(arc
							(start 0.1778 -0.2794)
							(mid 0.249642 -0.249642)
							(end 0.2794 -0.1778)
						)
						(arc
							(start 0.2794 0.1778)
							(mid 0.249642 0.249642)
							(end 0.1778 0.2794)
						)
					)
					(width 0)
					(fill yes)
				)
			)
		)
	)
	(footprint ""
		(layer "B.Cu")
		(at 209.325464 -84.021676)
		(property "Reference" "Q20"
			(at 0 0 0)
			(layer "B.SilkS")
			(hide yes)
			(effects
				(font
					(size 1.27 1.27)
				)
				(justify mirror)
			)
		)
		(property "Value" "2N7002K-1-GP"
			(at -0.127 -8.9662 0)
			(unlocked yes)
			(layer "B.Fab")
			(hide yes)
			(effects
				(font
					(size 1.016 1.016)
					(thickness 0.1524)
				)
				(justify mirror)
			)
		)
		(property "Device Type" "SOT23DGS2D4H44"
			(at -0.127 -10.4902 0)
			(unlocked yes)
			(layer "B.Fab")
			(hide yes)
			(effects
				(font
					(size 1.016 1.016)
					(thickness 0.1524)
				)
				(justify mirror)
			)
		)
		(duplicate_pad_numbers_are_jumpers no)
		(fp_line
			(start -1.651 -1.778)
			(end 1.651 -1.778)
			(stroke
				(width 0.1524)
				(type default)
			)
			(layer "B.SilkS")
		)
		(fp_line
			(start -1.651 1.778)
			(end -1.651 -1.778)
			(stroke
				(width 0.1524)
				(type default)
			)
			(layer "B.SilkS")
		)
		(fp_line
			(start 1.651 -1.778)
			(end 1.651 1.778)
			(stroke
				(width 0.1524)
				(type default)
			)
			(layer "B.SilkS")
		)
		(fp_line
			(start 1.651 1.778)
			(end -1.651 1.778)
			(stroke
				(width 0.1524)
				(type default)
			)
			(layer "B.SilkS")
		)
		(fp_poly
			(pts
				(xy 1.778 1.8796) (xy 1.778 -1.8796) (xy -1.778 -1.8796) (xy -1.778 1.8796)
			)
			(stroke
				(width 0)
				(type default)
			)
			(fill no)
			(layer "B.CrtYd")
		)
		(fp_poly
			(pts
				(xy 1.778 1.8796) (xy 1.778 -1.8796) (xy -1.778 -1.8796) (xy -1.778 1.8796)
			)
			(stroke
				(width 0)
				(type default)
			)
			(fill no)
			(layer "B.Fab")
		)
		(pad "D" smd custom
			(at 0 -0.9525 180)
			(size 0.1905 0.1905)
			(layers "B.Cu" "B.Mask" "B.Paste")
			(net "Q21_G")
			(options
				(clearance outline)
				(anchor circle)
			)
			(primitives
				(gr_poly
					(pts
						(arc
							(start -0.1778 -0.5715)
							(mid -0.321484 -0.511984)
							(end -0.381 -0.3683)
						)
						(arc
							(start -0.381 0.3683)
							(mid -0.321484 0.511984)
							(end -0.1778 0.5715)
						)
						(arc
							(start 0.1778 0.5715)
							(mid 0.321484 0.511984)
							(end 0.381 0.3683)
						)
						(arc
							(start 0.381 -0.3683)
							(mid 0.321484 -0.511984)
							(end 0.1778 -0.5715)
						)
					)
					(width 0)
					(fill yes)
				)
			)
		)
		(pad "G" smd custom
			(at 0.98425 0.9525 180)
			(size 0.1905 0.1905)
			(layers "B.Cu" "B.Mask" "B.Paste")
			(net "Q20_G")
			(options
				(clearance outline)
				(anchor circle)
			)
			(primitives
				(gr_poly
					(pts
						(arc
							(start -0.1778 -0.5715)
							(mid -0.321484 -0.511984)
							(end -0.381 -0.3683)
						)
						(arc
							(start -0.381 0.3683)
							(mid -0.321484 0.511984)
							(end -0.1778 0.5715)
						)
						(arc
							(start 0.1778 0.5715)
							(mid 0.321484 0.511984)
							(end 0.381 0.3683)
						)
						(arc
							(start 0.381 -0.3683)
							(mid 0.321484 -0.511984)
							(end 0.1778 -0.5715)
						)
					)
					(width 0)
					(fill yes)
				)
			)
		)
		(pad "S" smd custom
			(at -0.98425 0.9525 180)
			(size 0.1905 0.1905)
			(layers "B.Cu" "B.Mask" "B.Paste")
			(net "GND")
			(options
				(clearance outline)
				(anchor circle)
			)
			(primitives
				(gr_poly
					(pts
						(arc
							(start -0.1778 -0.5715)
							(mid -0.321484 -0.511984)
							(end -0.381 -0.3683)
						)
						(arc
							(start -0.381 0.3683)
							(mid -0.321484 0.511984)
							(end -0.1778 0.5715)
						)
						(arc
							(start 0.1778 0.5715)
							(mid 0.321484 0.511984)
							(end 0.381 0.3683)
						)
						(arc
							(start 0.381 -0.3683)
							(mid 0.321484 -0.511984)
							(end 0.1778 -0.5715)
						)
					)
					(width 0)
					(fill yes)
				)
			)
		)
	)
	(footprint ""
		(layer "B.Cu")
		(at 41.284398 -127.978916)
		(property "Reference" "R314"
			(at 0 0 0)
			(layer "B.SilkS")
			(hide yes)
			(effects
				(font
					(size 1.27 1.27)
				)
				(justify mirror)
			)
		)
		(property "Value" "0R2J-2-GP"
			(at -0.064008 -3.993896 0)
			(unlocked yes)
			(layer "B.Fab")
			(hide yes)
			(effects
				(font
					(size 1.016 1.016)
					(thickness 0.1524)
				)
				(justify mirror)
			)
		)
		(property "Device Type" "R402H16"
			(at -0.064008 -5.517896 0)
			(unlocked yes)
			(layer "B.Fab")
			(hide yes)
			(effects
				(font
					(size 1.016 1.016)
					(thickness 0.1524)
				)
				(justify mirror)
			)
		)
		(duplicate_pad_numbers_are_jumpers no)
		(fp_line
			(start -0.508 -0.9398)
			(end 0.508 -0.9398)
			(stroke
				(width 0.1524)
				(type default)
			)
			(layer "B.SilkS")
		)
		(fp_line
			(start 0.508 -0.9398)
			(end 0.508 0.9398)
			(stroke
				(width 0.1524)
				(type default)
			)
			(layer "B.SilkS")
		)
		(fp_rect
			(start 0.508 0.9398)
			(end -0.508 -0.9398)
			(stroke
				(width 0)
				(type default)
			)
			(fill no)
			(layer "B.CrtYd")
		)
		(fp_rect
			(start 0.508 0.9398)
			(end -0.508 -0.9398)
			(stroke
				(width 0)
				(type default)
			)
			(fill no)
			(layer "B.Fab")
		)
		(pad "1" smd custom
			(at 0 -0.4445 180)
			(size 0.1397 0.1397)
			(layers "B.Cu" "B.Mask" "B.Paste")
			(net "BMC_EXTRST_N")
			(options
				(clearance outline)
				(anchor circle)
			)
			(primitives
				(gr_poly
					(pts
						(arc
							(start -0.1778 0.2794)
							(mid -0.249642 0.249642)
							(end -0.2794 0.1778)
						)
						(arc
							(start -0.2794 -0.1778)
							(mid -0.249642 -0.249642)
							(end -0.1778 -0.2794)
						)
						(arc
							(start 0.1778 -0.2794)
							(mid 0.249642 -0.249642)
							(end 0.2794 -0.1778)
						)
						(arc
							(start 0.2794 0.1778)
							(mid 0.249642 0.249642)
							(end 0.1778 0.2794)
						)
					)
					(width 0)
					(fill yes)
				)
			)
		)
		(pad "2" smd custom
			(at 0 0.4445 180)
			(size 0.1397 0.1397)
			(layers "B.Cu" "B.Mask" "B.Paste")
			(net "RST_BMC_EXTRST_N")
			(options
				(clearance outline)
				(anchor circle)
			)
			(primitives
				(gr_poly
					(pts
						(arc
							(start -0.1778 0.2794)
							(mid -0.249642 0.249642)
							(end -0.2794 0.1778)
						)
						(arc
							(start -0.2794 -0.1778)
							(mid -0.249642 -0.249642)
							(end -0.1778 -0.2794)
						)
						(arc
							(start 0.1778 -0.2794)
							(mid 0.249642 -0.249642)
							(end 0.2794 -0.1778)
						)
						(arc
							(start 0.2794 0.1778)
							(mid 0.249642 0.249642)
							(end 0.1778 0.2794)
						)
					)
					(width 0)
					(fill yes)
				)
			)
		)
	)
	(footprint ""
		(layer "B.Cu")
		(at 55.309262 -134.134352 90)
		(property "Reference" "R784"
			(at 0 0 90)
			(layer "B.SilkS")
			(hide yes)
			(effects
				(font
					(size 1.27 1.27)
				)
				(justify mirror)
			)
		)
		(property "Value" "10KR2F-2-GP"
			(at -0.064008 -3.993896 90)
			(unlocked yes)
			(layer "B.Fab")
			(hide yes)
			(effects
				(font
					(size 1.016 1.016)
					(thickness 0.1524)
				)
				(justify mirror)
			)
		)
		(property "Device Type" "R402H16"
			(at -0.064008 -5.517896 90)
			(unlocked yes)
			(layer "B.Fab")
			(hide yes)
			(effects
				(font
					(size 1.016 1.016)
					(thickness 0.1524)
				)
				(justify mirror)
			)
		)
		(duplicate_pad_numbers_are_jumpers no)
		(fp_line
			(start 0.508 -0.9398)
			(end 0.508 0.9398)
			(stroke
				(width 0.1524)
				(type default)
			)
			(layer "B.SilkS")
		)
		(fp_line
			(start -0.508 -0.9398)
			(end 0.508 -0.9398)
			(stroke
				(width 0.1524)
				(type default)
			)
			(layer "B.SilkS")
		)
		(fp_rect
			(start 0.508 0.9398)
			(end -0.508 -0.9398)
			(stroke
				(width 0)
				(type default)
			)
			(fill no)
			(layer "B.CrtYd")
		)
		(fp_rect
			(start 0.508 0.9398)
			(end -0.508 -0.9398)
			(stroke
				(width 0)
				(type default)
			)
			(fill no)
			(layer "B.Fab")
		)
		(pad "1" smd custom
			(at 0 -0.4445 270)
			(size 0.1397 0.1397)
			(layers "B.Cu" "B.Mask" "B.Paste")
			(net "P3V3_STBY")
			(options
				(clearance outline)
				(anchor circle)
			)
			(primitives
				(gr_poly
					(pts
						(arc
							(start -0.1778 0.2794)
							(mid -0.249642 0.249642)
							(end -0.2794 0.1778)
						)
						(arc
							(start -0.2794 -0.1778)
							(mid -0.249642 -0.249642)
							(end -0.1778 -0.2794)
						)
						(arc
							(start 0.1778 -0.2794)
							(mid 0.249642 -0.249642)
							(end 0.2794 -0.1778)
						)
						(arc
							(start 0.2794 0.1778)
							(mid 0.249642 0.249642)
							(end 0.1778 0.2794)
						)
					)
					(width 0)
					(fill yes)
				)
			)
		)
		(pad "2" smd custom
			(at 0 0.4445 270)
			(size 0.1397 0.1397)
			(layers "B.Cu" "B.Mask" "B.Paste")
			(net "COMP_PWR_BTN_N")
			(options
				(clearance outline)
				(anchor circle)
			)
			(primitives
				(gr_poly
					(pts
						(arc
							(start -0.1778 0.2794)
							(mid -0.249642 0.249642)
							(end -0.2794 0.1778)
						)
						(arc
							(start -0.2794 -0.1778)
							(mid -0.249642 -0.249642)
							(end -0.1778 -0.2794)
						)
						(arc
							(start 0.1778 -0.2794)
							(mid 0.249642 -0.249642)
							(end 0.2794 -0.1778)
						)
						(arc
							(start 0.2794 0.1778)
							(mid 0.249642 0.249642)
							(end 0.1778 0.2794)
						)
					)
					(width 0)
					(fill yes)
				)
			)
		)
	)
)
